# BASEBOARD_FAB2 (Tioga Pass) — schematic netlist excerpt (pin names and nets, part order shuffled) for the footprints in the layout excerpt that follows; sources: Cadence DE-HDL packaged netlist, KiCad conversion of Wiwynn_Tioga_Pass_MB.brd

C25W23  CAP  1.0UF 16V 10% X6S  pkg 0402  page 149 : A = P1V15_AUX_BMC ; B = GND
R3T2  RES  33.2 1% CHIP  pkg 0402  page 153 : A = SPI_SWITCH_MISO ; B = SPI_MISO_R1
R7W21  RES  4.75K 1% CHIP  pkg 0402  page 118 : A = P3V3_STBY ; B = RST_BMC_SRST_R_N

(kicad_pcb
	(version 20260206)
	(generator "pcbnew")
	(generator_version "10.0")
	(general
		(thickness 1.6)
		(legacy_teardrops no)
	)
	(paper "A4")
	(title_block
		(title "Wiwynn_Tioga_Pass_MB.brd")
		(comment 1 "Tioga Pass / footprints 4348-4350 of 4770")
	)
	(layers
		(0 "F.Cu" signal "TOP")
		(4 "In1.Cu" signal "L2GND")
		(6 "In2.Cu" signal "L3")
		(8 "In3.Cu" signal "L4GND")
		(10 "In4.Cu" signal "L5")
		(12 "In5.Cu" signal "L6GND")
		(14 "In6.Cu" signal "L7VCC")
		(16 "In7.Cu" signal "L8VCC")
		(18 "In8.Cu" signal "L9GND")
		(20 "In9.Cu" signal "L10")
		(22 "In10.Cu" signal "L11GND")
		(24 "In11.Cu" signal "L12")
		(26 "In12.Cu" signal "L13GND")
		(2 "B.Cu" signal "BOTTOM")
		(9 "F.Adhes" user "F.Adhesive")
		(11 "B.Adhes" user "B.Adhesive")
		(13 "F.Paste" user "Package Geometry/Pastemask Top")
		(15 "B.Paste" user "Package Geometry/Pastemask Bottom")
		(5 "F.SilkS" user "Ref Des/Silkscreen Top")
		(7 "B.SilkS" user "Ref Des/Silkscreen Bottom")
		(1 "F.Mask" user "Board Geometry/Soldermask Top")
		(3 "B.Mask" user "Board Geometry/Soldermask Bottom")
		(17 "Dwgs.User" user "User.Drawings")
		(19 "Cmts.User" user "User.Comments")
		(21 "Eco1.User" user "User.Eco1")
		(23 "Eco2.User" user "User.Eco2")
		(25 "Edge.Cuts" user "Board Geometry/Outline")
		(27 "Margin" user)
		(31 "F.CrtYd" user "Package Geometry/Place Bound Top")
		(29 "B.CrtYd" user "Package Geometry/Place Bound Bottom")
		(35 "F.Fab" user "Ref Des/Assembly Top")
		(33 "B.Fab" user "Ref Des/Assembly Bottom")
	)
	(footprint ""
		(layer "B.Cu")
		(at 378.587 -49.276 90)
		(property "Reference" "R3T2"
			(at 0 0 90)
			(layer "B.SilkS")
			(hide yes)
			(effects
				(font
					(size 1.27 1.27)
				)
				(justify mirror)
			)
		)
		(property "Value" ""
			(at 0 0 90)
			(layer "B.Fab")
			(effects
				(font
					(size 1.27 1.27)
				)
				(justify mirror)
			)
		)
		(duplicate_pad_numbers_are_jumpers no)
		(fp_poly
			(pts
				(xy 0.2794 -0.1016) (xy -0.2794 -0.1016) (xy -0.2794 0.9906) (xy 0.2794 0.9906)
			)
			(stroke
				(width 0)
				(type default)
			)
			(fill no)
			(layer "B.CrtYd")
		)
		(fp_line
			(start 0.2794 -0.1016)
			(end 0.2794 0.9906)
			(stroke
				(width 0.1)
				(type default)
			)
			(layer "B.Fab")
		)
		(fp_line
			(start -0.2794 -0.1016)
			(end 0.2794 -0.1016)
			(stroke
				(width 0.1)
				(type default)
			)
			(layer "B.Fab")
		)
		(fp_line
			(start 0.2794 0.9906)
			(end -0.2794 0.9906)
			(stroke
				(width 0.1)
				(type default)
			)
			(layer "B.Fab")
		)
		(fp_line
			(start -0.2794 0.9906)
			(end -0.2794 -0.1016)
			(stroke
				(width 0.1)
				(type default)
			)
			(layer "B.Fab")
		)
		(pad "1" smd rect
			(at 0 0 270)
			(size 0.508 0.508)
			(layers "B.Cu" "B.Mask" "B.Paste")
			(net "SPI_SWITCH_MISO")
		)
		(pad "2" smd rect
			(at 0 0.889 270)
			(size 0.508 0.508)
			(layers "B.Cu" "B.Mask" "B.Paste")
			(net "SPI_MISO_R1")
		)
		(zone
			(layer "B.Cu")
			(hatch none 0.5)
			(connect_pads
				(clearance 0)
			)
			(min_thickness 0.25)
			(keepout
				(tracks allowed)
				(vias not_allowed)
				(pads allowed)
				(copperpour not_allowed)
				(footprints allowed)
			)
			(placement
				(enabled no)
				(sheetname "")
			)
			(fill
				(thermal_gap 0.5)
				(thermal_bridge_width 0.5)
				(island_removal_mode 0)
			)
			(polygon
				(pts
					(xy 378.841 -49.53) (xy 378.841 -49.022) (xy 379.222 -49.022) (xy 379.222 -49.53)
				)
			)
		)
		(zone
			(layer "B.Cu")
			(hatch none 0.5)
			(connect_pads
				(clearance 0)
			)
			(min_thickness 0.25)
			(keepout
				(tracks not_allowed)
				(vias allowed)
				(pads allowed)
				(copperpour not_allowed)
				(footprints allowed)
			)
			(placement
				(enabled no)
				(sheetname "")
			)
			(fill
				(thermal_gap 0.5)
				(thermal_bridge_width 0.5)
				(island_removal_mode 0)
			)
			(polygon
				(pts
					(xy 379.222 -49.53) (xy 379.222 -49.022) (xy 378.841 -49.022) (xy 378.841 -49.53)
				)
			)
		)
	)
	(footprint ""
		(layer "B.Cu")
		(at 412.3055 -34.925 90)
		(property "Reference" "C25W23"
			(at 0.8382 -0.67818 90)
			(unlocked yes)
			(layer "B.SilkS")
			(effects
				(font
					(size 0.4064 0.254)
					(thickness 0.1524)
				)
				(justify left mirror)
			)
		)
		(property "Value" ""
			(at 0 0 90)
			(layer "B.Fab")
			(effects
				(font
					(size 1.27 1.27)
				)
				(justify mirror)
			)
		)
		(duplicate_pad_numbers_are_jumpers no)
		(fp_poly
			(pts
				(xy -0.3048 -0.1016) (xy -0.3048 0.9906) (xy 0.3048 0.9906) (xy 0.3048 -0.1016)
			)
			(stroke
				(width 0)
				(type default)
			)
			(fill no)
			(layer "B.CrtYd")
		)
		(fp_line
			(start 0.3048 -0.1016)
			(end 0.3048 0.9906)
			(stroke
				(width 0.1)
				(type default)
			)
			(layer "B.Fab")
		)
		(fp_line
			(start -0.3048 -0.1016)
			(end 0.3048 -0.1016)
			(stroke
				(width 0.1)
				(type default)
			)
			(layer "B.Fab")
		)
		(fp_line
			(start 0.3048 0.9906)
			(end -0.3048 0.9906)
			(stroke
				(width 0.1)
				(type default)
			)
			(layer "B.Fab")
		)
		(fp_line
			(start -0.3048 0.9906)
			(end -0.3048 -0.1016)
			(stroke
				(width 0.1)
				(type default)
			)
			(layer "B.Fab")
		)
		(pad "1" smd rect
			(at 0 0 270)
			(size 0.508 0.508)
			(layers "B.Cu" "B.Mask" "B.Paste")
			(net "P1V15_AUX_BMC")
		)
		(pad "2" smd rect
			(at 0 0.889 270)
			(size 0.508 0.508)
			(layers "B.Cu" "B.Mask" "B.Paste")
			(net "GND")
		)
		(zone
			(layer "B.Cu")
			(hatch none 0.5)
			(connect_pads
				(clearance 0)
			)
			(min_thickness 0.25)
			(keepout
				(tracks allowed)
				(vias not_allowed)
				(pads allowed)
				(copperpour not_allowed)
				(footprints allowed)
			)
			(placement
				(enabled no)
				(sheetname "")
			)
			(fill
				(thermal_gap 0.5)
				(thermal_bridge_width 0.5)
				(island_removal_mode 0)
			)
			(polygon
				(pts
					(xy 412.5595 -35.179) (xy 412.5595 -34.671) (xy 412.9405 -34.671) (xy 412.9405 -35.179)
				)
			)
		)
		(zone
			(layer "B.Cu")
			(hatch none 0.5)
			(connect_pads
				(clearance 0)
			)
			(min_thickness 0.25)
			(keepout
				(tracks not_allowed)
				(vias allowed)
				(pads allowed)
				(copperpour not_allowed)
				(footprints allowed)
			)
			(placement
				(enabled no)
				(sheetname "")
			)
			(fill
				(thermal_gap 0.5)
				(thermal_bridge_width 0.5)
				(island_removal_mode 0)
			)
			(polygon
				(pts
					(xy 412.9405 -35.179) (xy 412.9405 -34.671) (xy 412.5595 -34.671) (xy 412.5595 -35.179)
				)
			)
		)
	)
	(footprint ""
		(layer "B.Cu")
		(at 368.189256 -92.100654 90)
		(property "Reference" "R7W21"
			(at 0.8382 -0.67818 90)
			(unlocked yes)
			(layer "B.SilkS")
			(effects
				(font
					(size 0.4064 0.254)
					(thickness 0.1524)
				)
				(justify left mirror)
			)
		)
		(property "Value" ""
			(at 0 0 90)
			(layer "B.Fab")
			(effects
				(font
					(size 1.27 1.27)
				)
				(justify mirror)
			)
		)
		(duplicate_pad_numbers_are_jumpers no)
		(fp_poly
			(pts
				(xy 0.2794 -0.1016) (xy -0.2794 -0.1016) (xy -0.2794 0.9906) (xy 0.2794 0.9906)
			)
			(stroke
				(width 0)
				(type default)
			)
			(fill no)
			(layer "B.CrtYd")
		)
		(fp_line
			(start 0.2794 -0.1016)
			(end 0.2794 0.9906)
			(stroke
				(width 0.1)
				(type default)
			)
			(layer "B.Fab")
		)
		(fp_line
			(start -0.2794 -0.1016)
			(end 0.2794 -0.1016)
			(stroke
				(width 0.1)
				(type default)
			)
			(layer "B.Fab")
		)
		(fp_line
			(start 0.2794 0.9906)
			(end -0.2794 0.9906)
			(stroke
				(width 0.1)
				(type default)
			)
			(layer "B.Fab")
		)
		(fp_line
			(start -0.2794 0.9906)
			(end -0.2794 -0.1016)
			(stroke
				(width 0.1)
				(type default)
			)
			(layer "B.Fab")
		)
		(pad "1" smd rect
			(at 0 0 270)
			(size 0.508 0.508)
			(layers "B.Cu" "B.Mask" "B.Paste")
			(net "P3V3_STBY")
		)
		(pad "2" smd rect
			(at 0 0.889 270)
			(size 0.508 0.508)
			(layers "B.Cu" "B.Mask" "B.Paste")
			(net "RST_BMC_SRST_R_N")
		)
		(zone
			(layer "B.Cu")
			(hatch none 0.5)
			(connect_pads
				(clearance 0)
			)
			(min_thickness 0.25)
			(keepout
				(tracks allowed)
				(vias not_allowed)
				(pads allowed)
				(copperpour not_allowed)
				(footprints allowed)
			)
			(placement
				(enabled no)
				(sheetname "")
			)
			(fill
				(thermal_gap 0.5)
				(thermal_bridge_width 0.5)
				(island_removal_mode 0)
			)
			(polygon
				(pts
					(xy 368.443256 -92.354654) (xy 368.443256 -91.846654) (xy 368.824256 -91.846654) (xy 368.824256 -92.354654)
				)
			)
		)
		(zone
			(layer "B.Cu")
			(hatch none 0.5)
			(connect_pads
				(clearance 0)
			)
			(min_thickness 0.25)
			(keepout
				(tracks not_allowed)
				(vias allowed)
				(pads allowed)
				(copperpour not_allowed)
				(footprints allowed)
			)
			(placement
				(enabled no)
				(sheetname "")
			)
			(fill
				(thermal_gap 0.5)
				(thermal_bridge_width 0.5)
				(island_removal_mode 0)
			)
			(polygon
				(pts
					(xy 368.824256 -92.354654) (xy 368.824256 -91.846654) (xy 368.443256 -91.846654) (xy 368.443256 -92.354654)
				)
			)
		)
	)
)
